(kicad_pcb
	(version 20260206)
	(generator "pcbnew")
	(generator_version "10.0")
	(general
		(thickness 1.6)
		(legacy_teardrops no)
	)
	(paper "A4")
	(title_block
		(title "03242023_DA0F0TMBIJ0_F0T_Motherboard_J_brd_V01_OCP.brd")
		(comment 1 "Grand Teton / footprints 2547-2552 of 6105")
	)
	(layers
		(0 "F.Cu" signal "TOP")
		(4 "In1.Cu" signal "GND")
		(6 "In2.Cu" signal "IN1")
		(8 "In3.Cu" signal "GND1")
		(10 "In4.Cu" signal "IN2")
		(12 "In5.Cu" signal "GND2")
		(14 "In6.Cu" signal "IN3")
		(16 "In7.Cu" signal "GND3")
		(18 "In8.Cu" signal "VCC")
		(20 "In9.Cu" signal "VCC1")
		(22 "In10.Cu" signal "GND4")
		(24 "In11.Cu" signal "IN4")
		(26 "In12.Cu" signal "GND5")
		(28 "In13.Cu" signal "IN5")
		(30 "In14.Cu" signal "GND6")
		(32 "In15.Cu" signal "IN6")
		(34 "In16.Cu" signal "GND7")
		(2 "B.Cu" signal "BOTTOM")
		(9 "F.Adhes" user "F.Adhesive")
		(11 "B.Adhes" user "B.Adhesive")
		(13 "F.Paste" user "Package Geometry/Pastemask Top")
		(15 "B.Paste" user "Package Geometry/Pastemask Bottom")
		(5 "F.SilkS" user "Ref Des/Silkscreen Top")
		(7 "B.SilkS" user "Ref Des/Silkscreen Bottom")
		(1 "F.Mask" user "Board Geometry/Soldermask Top")
		(3 "B.Mask" user "Board Geometry/Soldermask Bottom")
		(17 "Dwgs.User" user "User.Drawings")
		(19 "Cmts.User" user "User.Comments")
		(21 "Eco1.User" user "User.Eco1")
		(23 "Eco2.User" user "User.Eco2")
		(25 "Edge.Cuts" user "Board Geometry/Outline")
		(27 "Margin" user)
		(31 "F.CrtYd" user "Package Geometry/Place Bound Top")
		(29 "B.CrtYd" user "Package Geometry/Place Bound Bottom")
		(35 "F.Fab" user "Ref Des/Assembly Top")
		(33 "B.Fab" user "Ref Des/Assembly Bottom")
	)
	(footprint ""
		(layer "F.Cu")
		(at 117.526816 -251.375672 90)
		(property "Reference" "C297"
			(at 0 0 90)
			(layer "F.SilkS")
			(hide yes)
			(effects
				(font
					(size 1.27 1.27)
				)
			)
		)
		(property "Value" ""
			(at 0 0 90)
			(layer "F.Fab")
			(effects
				(font
					(size 1.27 1.27)
				)
			)
		)
		(duplicate_pad_numbers_are_jumpers no)
		(fp_line
			(start 0.7874 -0.4064)
			(end 0.7874 0.4064)
			(stroke
				(width 0.1524)
				(type default)
			)
			(layer "F.SilkS")
		)
		(fp_line
			(start -0.7874 -0.4064)
			(end 0.7874 -0.4064)
			(stroke
				(width 0.1524)
				(type default)
			)
			(layer "F.SilkS")
		)
		(fp_line
			(start 0.7874 0.4064)
			(end -0.7874 0.4064)
			(stroke
				(width 0.1524)
				(type default)
			)
			(layer "F.SilkS")
		)
		(fp_line
			(start -0.7874 0.4064)
			(end -0.7874 -0.4064)
			(stroke
				(width 0.1524)
				(type default)
			)
			(layer "F.SilkS")
		)
		(fp_line
			(start -0.12065 -0.305054)
			(end -0.12065 -0.2794)
			(stroke
				(width 0.1)
				(type default)
			)
			(layer "F.Fab")
		)
		(fp_line
			(start -0.67945 -0.305054)
			(end -0.12065 -0.305054)
			(stroke
				(width 0.1)
				(type default)
			)
			(layer "F.Fab")
		)
		(fp_line
			(start 0.67945 -0.3048)
			(end 0.67945 0.3048)
			(stroke
				(width 0.1)
				(type default)
			)
			(layer "F.Fab")
		)
		(fp_line
			(start 0.12065 -0.3048)
			(end 0.67945 -0.3048)
			(stroke
				(width 0.1)
				(type default)
			)
			(layer "F.Fab")
		)
		(fp_line
			(start 0.12065 -0.2794)
			(end 0.12065 -0.3048)
			(stroke
				(width 0.1)
				(type default)
			)
			(layer "F.Fab")
		)
		(fp_line
			(start -0.12065 -0.2794)
			(end 0.12065 -0.2794)
			(stroke
				(width 0.1)
				(type default)
			)
			(layer "F.Fab")
		)
		(fp_line
			(start 0.120396 0.2794)
			(end -0.12065 0.2794)
			(stroke
				(width 0.1)
				(type default)
			)
			(layer "F.Fab")
		)
		(fp_line
			(start -0.12065 0.2794)
			(end -0.12065 0.3048)
			(stroke
				(width 0.1)
				(type default)
			)
			(layer "F.Fab")
		)
		(fp_line
			(start 0.67945 0.3048)
			(end 0.120396 0.3048)
			(stroke
				(width 0.1)
				(type default)
			)
			(layer "F.Fab")
		)
		(fp_line
			(start 0.120396 0.3048)
			(end 0.120396 0.2794)
			(stroke
				(width 0.1)
				(type default)
			)
			(layer "F.Fab")
		)
		(fp_line
			(start -0.12065 0.3048)
			(end -0.67945 0.3048)
			(stroke
				(width 0.1)
				(type default)
			)
			(layer "F.Fab")
		)
		(fp_line
			(start -0.67945 0.3048)
			(end -0.67945 -0.305054)
			(stroke
				(width 0.1)
				(type default)
			)
			(layer "F.Fab")
		)
		(pad "1" smd circle
			(at -0.40005 0 90)
			(size 0 0)
			(layers "F.Cu" "F.Mask" "F.Paste")
			(net "PVCCIN_CPU1")
		)
		(pad "2" smd circle
			(at 0.40005 0 90)
			(size 0 0)
			(layers "F.Cu" "F.Mask" "F.Paste")
			(net "GND")
		)
	)
	(footprint ""
		(layer "F.Cu")
		(at 378.303536 -105.483152 -90)
		(property "Reference" "R1367"
			(at 0 0 270)
			(layer "F.SilkS")
			(hide yes)
			(effects
				(font
					(size 1.27 1.27)
				)
			)
		)
		(property "Value" ""
			(at 0 0 270)
			(layer "F.Fab")
			(effects
				(font
					(size 1.27 1.27)
				)
			)
		)
		(duplicate_pad_numbers_are_jumpers no)
		(fp_line
			(start -0.7874 0.4064)
			(end -0.7874 -0.4064)
			(stroke
				(width 0.1524)
				(type default)
			)
			(layer "F.SilkS")
		)
		(fp_line
			(start 0.7874 0.4064)
			(end -0.7874 0.4064)
			(stroke
				(width 0.1524)
				(type default)
			)
			(layer "F.SilkS")
		)
		(fp_line
			(start -0.7874 -0.4064)
			(end 0.7874 -0.4064)
			(stroke
				(width 0.1524)
				(type default)
			)
			(layer "F.SilkS")
		)
		(fp_line
			(start 0.7874 -0.4064)
			(end 0.7874 0.4064)
			(stroke
				(width 0.1524)
				(type default)
			)
			(layer "F.SilkS")
		)
		(fp_line
			(start -0.67945 0.3048)
			(end -0.67945 -0.305054)
			(stroke
				(width 0.1)
				(type default)
			)
			(layer "F.Fab")
		)
		(fp_line
			(start -0.12065 0.3048)
			(end -0.67945 0.3048)
			(stroke
				(width 0.1)
				(type default)
			)
			(layer "F.Fab")
		)
		(fp_line
			(start 0.120396 0.3048)
			(end 0.120396 0.2794)
			(stroke
				(width 0.1)
				(type default)
			)
			(layer "F.Fab")
		)
		(fp_line
			(start 0.67945 0.3048)
			(end 0.120396 0.3048)
			(stroke
				(width 0.1)
				(type default)
			)
			(layer "F.Fab")
		)
		(fp_line
			(start -0.12065 0.2794)
			(end -0.12065 0.3048)
			(stroke
				(width 0.1)
				(type default)
			)
			(layer "F.Fab")
		)
		(fp_line
			(start 0.120396 0.2794)
			(end -0.12065 0.2794)
			(stroke
				(width 0.1)
				(type default)
			)
			(layer "F.Fab")
		)
		(fp_line
			(start -0.12065 -0.2794)
			(end 0.12065 -0.2794)
			(stroke
				(width 0.1)
				(type default)
			)
			(layer "F.Fab")
		)
		(fp_line
			(start 0.12065 -0.2794)
			(end 0.12065 -0.3048)
			(stroke
				(width 0.1)
				(type default)
			)
			(layer "F.Fab")
		)
		(fp_line
			(start 0.12065 -0.3048)
			(end 0.67945 -0.3048)
			(stroke
				(width 0.1)
				(type default)
			)
			(layer "F.Fab")
		)
		(fp_line
			(start 0.67945 -0.3048)
			(end 0.67945 0.3048)
			(stroke
				(width 0.1)
				(type default)
			)
			(layer "F.Fab")
		)
		(fp_line
			(start -0.67945 -0.305054)
			(end -0.12065 -0.305054)
			(stroke
				(width 0.1)
				(type default)
			)
			(layer "F.Fab")
		)
		(fp_line
			(start -0.12065 -0.305054)
			(end -0.12065 -0.2794)
			(stroke
				(width 0.1)
				(type default)
			)
			(layer "F.Fab")
		)
		(pad "1" smd circle
			(at -0.40005 0 270)
			(size 0 0)
			(layers "F.Cu" "F.Mask" "F.Paste")
			(net "JTAG_DBP_PRDY_N")
		)
		(pad "2" smd circle
			(at 0.40005 0 270)
			(size 0 0)
			(layers "F.Cu" "F.Mask" "F.Paste")
			(net "JTAG_DBP_PRDY_R_N")
		)
	)
	(footprint ""
		(layer "F.Cu")
		(at 527.948906 -153.205688 -90)
		(property "Reference" "X7"
			(at -1.2954 2.72923 90)
			(unlocked yes)
			(layer "F.SilkS")
			(effects
				(font
					(size 0.7874 0.5842)
					(thickness 0.1524)
				)
				(justify left)
			)
		)
		(property "Value" ""
			(at 0 0 270)
			(layer "F.Fab")
			(effects
				(font
					(size 1.27 1.27)
				)
			)
		)
		(property "Device Type" "TP_TDR_4P_FTS_MPKT4_H025P0200_I"
			(at 1.30175 1.27 0)
			(unlocked yes)
			(layer "F.Fab")
			(hide yes)
			(effects
				(font
					(size 0.635 0.4064)
					(thickness 0.1524)
				)
			)
		)
		(property "User Part Number" "TP15"
			(at 1.30175 1.27 0)
			(unlocked yes)
			(layer "Cmts.User")
			(hide yes)
			(effects
				(font
					(size 0.635 0.4064)
					(thickness 0.1524)
				)
			)
		)
		(duplicate_pad_numbers_are_jumpers no)
		(fp_line
			(start 0 3.81)
			(end 2.54 3.81)
			(stroke
				(width 0.1524)
				(type default)
			)
			(layer "F.SilkS")
		)
		(fp_line
			(start 2.54 3.81)
			(end 2.54 3.6703)
			(stroke
				(width 0.1524)
				(type default)
			)
			(layer "F.SilkS")
		)
		(fp_line
			(start 0 3.175)
			(end 0 3.81)
			(stroke
				(width 0.1524)
				(type default)
			)
			(layer "F.SilkS")
		)
		(fp_line
			(start 2.54 1.4097)
			(end 2.54 1.1303)
			(stroke
				(width 0.1524)
				(type default)
			)
			(layer "F.SilkS")
		)
		(fp_line
			(start 0 0.635)
			(end 0 1.905)
			(stroke
				(width 0.1524)
				(type default)
			)
			(layer "F.SilkS")
		)
		(fp_line
			(start 2.54 -1.1303)
			(end 2.54 -1.27)
			(stroke
				(width 0.1524)
				(type default)
			)
			(layer "F.SilkS")
		)
		(fp_line
			(start 0 -1.27)
			(end 0 -0.635)
			(stroke
				(width 0.1524)
				(type default)
			)
			(layer "F.SilkS")
		)
		(fp_line
			(start 2.54 -1.27)
			(end 0 -1.27)
			(stroke
				(width 0.1524)
				(type default)
			)
			(layer "F.SilkS")
		)
		(fp_poly
			(pts
				(xy -1.287526 0.08382) (xy -2.811526 0.84582) (xy -2.811526 -0.67818)
			)
			(stroke
				(width 0)
				(type default)
			)
			(fill yes)
			(layer "F.SilkS")
		)
		(fp_line
			(start 0 3.81)
			(end 2.54 3.81)
			(stroke
				(width 0.1)
				(type default)
			)
			(layer "F.Fab")
		)
		(fp_line
			(start 2.54 3.81)
			(end 2.54 -1.27)
			(stroke
				(width 0.1)
				(type default)
			)
			(layer "F.Fab")
		)
		(fp_line
			(start 0 -1.27)
			(end 0 3.81)
			(stroke
				(width 0.1)
				(type default)
			)
			(layer "F.Fab")
		)
		(fp_line
			(start 2.54 -1.27)
			(end 0 -1.27)
			(stroke
				(width 0.1)
				(type default)
			)
			(layer "F.Fab")
		)
		(fp_poly
			(pts
				(xy -0.761746 0) (xy -2.285746 -0.762) (xy -2.285746 0.762)
			)
			(stroke
				(width 0)
				(type default)
			)
			(fill yes)
			(layer "F.Fab")
		)
		(pad "1" thru_hole circle
			(at 0 0 270)
			(size 1.0033 1.0033)
			(drill 0.249936)
			(layers "*.Cu" "*.Mask")
			(remove_unused_layers no)
			(net "TDR_DIFF_85_TOP_DN")
			(clearance 0.10795)
			(thermal_gap 0.10795)
			(padstack
				(mode front_inner_back)
				(layer "Inner"
					(shape circle)
					(size 0.8001 0.8001)
					(clearance 0.1524)
				)
				(layer "B.Cu"
					(shape circle)
					(size 1.0033 1.0033)
					(clearance 0.10795)
				)
			)
		)
		(pad "2" thru_hole circle
			(at 2.54 0 270)
			(size 1.9939 1.9939)
			(drill 0.249936)
			(layers "*.Cu" "*.Mask")
			(remove_unused_layers no)
			(net "T1_GND")
			(clearance 0.10795)
			(thermal_gap 0.10795)
			(padstack
				(mode front_inner_back)
				(layer "Inner"
					(shape circle)
					(size 0.8001 0.8001)
					(clearance 0.1524)
				)
				(layer "B.Cu"
					(shape circle)
					(size 1.9939 1.9939)
					(clearance 0.10795)
				)
			)
		)
		(pad "3" thru_hole circle
			(at 2.54 2.54 270)
			(size 1.9939 1.9939)
			(drill 0.249936)
			(layers "*.Cu" "*.Mask")
			(remove_unused_layers no)
			(net "T1_GND")
			(clearance 0.10795)
			(thermal_gap 0.10795)
			(padstack
				(mode front_inner_back)
				(layer "Inner"
					(shape circle)
					(size 0.8001 0.8001)
					(clearance 0.1524)
				)
				(layer "B.Cu"
					(shape circle)
					(size 1.9939 1.9939)
					(clearance 0.10795)
				)
			)
		)
		(pad "4" thru_hole circle
			(at 0 2.54 270)
			(size 1.0033 1.0033)
			(drill 0.249936)
			(layers "*.Cu" "*.Mask")
			(remove_unused_layers no)
			(net "TDR_DIFF_85_TOP_DP")
			(clearance 0.10795)
			(thermal_gap 0.10795)
			(padstack
				(mode front_inner_back)
				(layer "Inner"
					(shape circle)
					(size 0.8001 0.8001)
					(clearance 0.1524)
				)
				(layer "B.Cu"
					(shape circle)
					(size 1.0033 1.0033)
					(clearance 0.10795)
				)
			)
		)
	)
	(footprint ""
		(layer "F.Cu")
		(at 15.436596 -386.103876)
		(property "Reference" "R3266"
			(at 0 0 0)
			(layer "F.SilkS")
			(hide yes)
			(effects
				(font
					(size 1.27 1.27)
				)
			)
		)
		(property "Value" ""
			(at 0 0 0)
			(layer "F.Fab")
			(effects
				(font
					(size 1.27 1.27)
				)
			)
		)
		(duplicate_pad_numbers_are_jumpers no)
		(fp_line
			(start -0.7874 -0.4064)
			(end 0.7874 -0.4064)
			(stroke
				(width 0.1524)
				(type default)
			)
			(layer "F.SilkS")
		)
		(fp_line
			(start -0.7874 0.4064)
			(end -0.7874 -0.4064)
			(stroke
				(width 0.1524)
				(type default)
			)
			(layer "F.SilkS")
		)
		(fp_line
			(start 0.7874 -0.4064)
			(end 0.7874 0.4064)
			(stroke
				(width 0.1524)
				(type default)
			)
			(layer "F.SilkS")
		)
		(fp_line
			(start 0.7874 0.4064)
			(end -0.7874 0.4064)
			(stroke
				(width 0.1524)
				(type default)
			)
			(layer "F.SilkS")
		)
		(fp_line
			(start -0.67945 -0.305054)
			(end -0.12065 -0.305054)
			(stroke
				(width 0.1)
				(type default)
			)
			(layer "F.Fab")
		)
		(fp_line
			(start -0.67945 0.3048)
			(end -0.67945 -0.305054)
			(stroke
				(width 0.1)
				(type default)
			)
			(layer "F.Fab")
		)
		(fp_line
			(start -0.12065 -0.305054)
			(end -0.12065 -0.2794)
			(stroke
				(width 0.1)
				(type default)
			)
			(layer "F.Fab")
		)
		(fp_line
			(start -0.12065 -0.2794)
			(end 0.12065 -0.2794)
			(stroke
				(width 0.1)
				(type default)
			)
			(layer "F.Fab")
		)
		(fp_line
			(start -0.12065 0.2794)
			(end -0.12065 0.3048)
			(stroke
				(width 0.1)
				(type default)
			)
			(layer "F.Fab")
		)
		(fp_line
			(start -0.12065 0.3048)
			(end -0.67945 0.3048)
			(stroke
				(width 0.1)
				(type default)
			)
			(layer "F.Fab")
		)
		(fp_line
			(start 0.120396 0.2794)
			(end -0.12065 0.2794)
			(stroke
				(width 0.1)
				(type default)
			)
			(layer "F.Fab")
		)
		(fp_line
			(start 0.120396 0.3048)
			(end 0.120396 0.2794)
			(stroke
				(width 0.1)
				(type default)
			)
			(layer "F.Fab")
		)
		(fp_line
			(start 0.12065 -0.3048)
			(end 0.67945 -0.3048)
			(stroke
				(width 0.1)
				(type default)
			)
			(layer "F.Fab")
		)
		(fp_line
			(start 0.12065 -0.2794)
			(end 0.12065 -0.3048)
			(stroke
				(width 0.1)
				(type default)
			)
			(layer "F.Fab")
		)
		(fp_line
			(start 0.67945 -0.3048)
			(end 0.67945 0.3048)
			(stroke
				(width 0.1)
				(type default)
			)
			(layer "F.Fab")
		)
		(fp_line
			(start 0.67945 0.3048)
			(end 0.120396 0.3048)
			(stroke
				(width 0.1)
				(type default)
			)
			(layer "F.Fab")
		)
		(pad "1" smd circle
			(at -0.40005 0)
			(size 0 0)
			(layers "F.Cu" "F.Mask" "F.Paste")
			(net "P3V3_AUX")
		)
		(pad "2" smd circle
			(at 0.40005 0)
			(size 0 0)
			(layers "F.Cu" "F.Mask" "F.Paste")
			(net "FM_P2E_MODE")
		)
	)
	(footprint ""
		(layer "F.Cu")
		(at 102.827074 -354.847652)
		(property "Reference" "R2550"
			(at 0 0 0)
			(layer "F.SilkS")
			(hide yes)
			(effects
				(font
					(size 1.27 1.27)
				)
			)
		)
		(property "Value" ""
			(at 0 0 0)
			(layer "F.Fab")
			(effects
				(font
					(size 1.27 1.27)
				)
			)
		)
		(duplicate_pad_numbers_are_jumpers no)
		(fp_line
			(start -0.7874 -0.4064)
			(end 0.7874 -0.4064)
			(stroke
				(width 0.1524)
				(type default)
			)
			(layer "F.SilkS")
		)
		(fp_line
			(start -0.7874 0.4064)
			(end -0.7874 -0.4064)
			(stroke
				(width 0.1524)
				(type default)
			)
			(layer "F.SilkS")
		)
		(fp_line
			(start 0.7874 -0.4064)
			(end 0.7874 0.4064)
			(stroke
				(width 0.1524)
				(type default)
			)
			(layer "F.SilkS")
		)
		(fp_line
			(start 0.7874 0.4064)
			(end -0.7874 0.4064)
			(stroke
				(width 0.1524)
				(type default)
			)
			(layer "F.SilkS")
		)
		(fp_line
			(start -0.67945 -0.305054)
			(end -0.12065 -0.305054)
			(stroke
				(width 0.1)
				(type default)
			)
			(layer "F.Fab")
		)
		(fp_line
			(start -0.67945 0.3048)
			(end -0.67945 -0.305054)
			(stroke
				(width 0.1)
				(type default)
			)
			(layer "F.Fab")
		)
		(fp_line
			(start -0.12065 -0.305054)
			(end -0.12065 -0.2794)
			(stroke
				(width 0.1)
				(type default)
			)
			(layer "F.Fab")
		)
		(fp_line
			(start -0.12065 -0.2794)
			(end 0.12065 -0.2794)
			(stroke
				(width 0.1)
				(type default)
			)
			(layer "F.Fab")
		)
		(fp_line
			(start -0.12065 0.2794)
			(end -0.12065 0.3048)
			(stroke
				(width 0.1)
				(type default)
			)
			(layer "F.Fab")
		)
		(fp_line
			(start -0.12065 0.3048)
			(end -0.67945 0.3048)
			(stroke
				(width 0.1)
				(type default)
			)
			(layer "F.Fab")
		)
		(fp_line
			(start 0.120396 0.2794)
			(end -0.12065 0.2794)
			(stroke
				(width 0.1)
				(type default)
			)
			(layer "F.Fab")
		)
		(fp_line
			(start 0.120396 0.3048)
			(end 0.120396 0.2794)
			(stroke
				(width 0.1)
				(type default)
			)
			(layer "F.Fab")
		)
		(fp_line
			(start 0.12065 -0.3048)
			(end 0.67945 -0.3048)
			(stroke
				(width 0.1)
				(type default)
			)
			(layer "F.Fab")
		)
		(fp_line
			(start 0.12065 -0.2794)
			(end 0.12065 -0.3048)
			(stroke
				(width 0.1)
				(type default)
			)
			(layer "F.Fab")
		)
		(fp_line
			(start 0.67945 -0.3048)
			(end 0.67945 0.3048)
			(stroke
				(width 0.1)
				(type default)
			)
			(layer "F.Fab")
		)
		(fp_line
			(start 0.67945 0.3048)
			(end 0.120396 0.3048)
			(stroke
				(width 0.1)
				(type default)
			)
			(layer "F.Fab")
		)
		(pad "1" smd circle
			(at -0.40005 0)
			(size 0 0)
			(layers "F.Cu" "F.Mask" "F.Paste")
			(net "FM_PVCCFA_EHV_FIVRA_CPU1_EN")
		)
		(pad "2" smd circle
			(at 0.40005 0)
			(size 0 0)
			(layers "F.Cu" "F.Mask" "F.Paste")
			(net "PVCCFA_EHV_FIVRA_CPU1_EN_R")
		)
	)
	(footprint ""
		(layer "F.Cu")
		(at 279.6032 -65.877948)
		(property "Reference" "PC1227"
			(at 0 0 0)
			(layer "F.SilkS")
			(hide yes)
			(effects
				(font
					(size 1.27 1.27)
				)
			)
		)
		(property "Value" ""
			(at 0 0 0)
			(layer "F.Fab")
			(effects
				(font
					(size 1.27 1.27)
				)
			)
		)
		(duplicate_pad_numbers_are_jumpers no)
		(fp_line
			(start 2.750058 0.999998)
			(end -2.750058 0.999998)
			(stroke
				(width 0.1524)
				(type default)
			)
			(layer "F.SilkS")
		)
		(fp_circle
			(center 0 0.999998)
			(end 2.750058 0.999998)
			(stroke
				(width 0.1524)
				(type default)
			)
			(fill no)
			(layer "F.SilkS")
		)
		(fp_poly
			(pts
				(arc
					(start 2.750058 0.999998)
					(mid 0 3.750056)
					(end -2.750058 0.999998)
				)
			)
			(stroke
				(width 0)
				(type default)
			)
			(fill yes)
			(layer "F.SilkS")
		)
		(fp_circle
			(center 0 0.999998)
			(end 2.750058 0.999998)
			(stroke
				(width 0.1)
				(type default)
			)
			(fill no)
			(layer "F.Fab")
		)
		(pad "1" thru_hole rect
			(at 0 0)
			(size 1.5748 1.5748)
			(drill 1.0668)
			(layers "*.Cu" "*.Mask")
			(remove_unused_layers no)
			(net "P1V05_PCH_AUX")
			(clearance 0)
			(padstack
				(mode front_inner_back)
				(layer "Inner"
					(shape circle)
					(size 1.5748 1.5748)
					(clearance 0)
				)
				(layer "B.Cu"
					(shape rect)
					(size 1.5748 1.5748)
					(clearance 0)
				)
			)
		)
		(pad "2" thru_hole circle
			(at 0 1.999996)
			(size 1.5748 1.5748)
			(drill 1.0668)
			(layers "*.Cu" "*.Mask")
			(remove_unused_layers no)
			(net "GND")
			(clearance 0)
		)
	)
)
